(kicad_pcb
	(version 20241229)
	(generator "pcbnew")
	(generator_version "9.0")
	(general
		(thickness 1.6)
		(legacy_teardrops no)
	)
	(paper "A4")
	(title_block
		(title "GMSL Deserializer")
		(date "2025-10-09")
		(rev "1.0.4")
		(company "Antmicro Ltd")
		(comment 1 "www.antmicro.com")
		(comment 9 "footprints 124-128 of 235")
	)
	(layers
		(0 "F.Cu" signal)
		(4 "In1.Cu" power)
		(6 "In2.Cu" power)
		(2 "B.Cu" signal)
		(9 "F.Adhes" user "F.Adhesive")
		(11 "B.Adhes" user "B.Adhesive")
		(13 "F.Paste" user)
		(15 "B.Paste" user)
		(5 "F.SilkS" user "F.Silkscreen")
		(7 "B.SilkS" user "B.Silkscreen")
		(1 "F.Mask" user)
		(3 "B.Mask" user)
		(17 "Dwgs.User" user "User.Drawings")
		(19 "Cmts.User" user "User.Comments")
		(21 "Eco1.User" user "User.Eco1")
		(23 "Eco2.User" user "User.Eco2")
		(25 "Edge.Cuts" user)
		(27 "Margin" user)
		(31 "F.CrtYd" user "F.Courtyard")
		(29 "B.CrtYd" user "B.Courtyard")
		(35 "F.Fab" user)
		(33 "B.Fab" user)
	)
	(footprint "antmicro-footprints:LED_0603_1608Metric_G"
		(layer "F.Cu")
		(at 149.352 96.1 -90)
		(descr "LED SMD 0603 Green")
		(tags "LED SMD 0603 Green")
		(property "Reference" "D17"
			(at -3.616666 30.935333 0)
			(layer "F.SilkS")
			(effects
				(font
					(size 0.7 0.7)
					(thickness 0.15)
				)
				(justify right bottom)
			)
		)
		(property "Value" "LED_G_0603_LTST-C190GKT"
			(at -0.001 1.599 90)
			(layer "F.Fab")
			(effects
				(font
					(size 0.7 0.7)
					(thickness 0.15)
				)
				(justify right bottom)
			)
		)
		(property "Datasheet" "https://media.digikey.com/pdf/Data%20Sheets/Lite-On%20PDFs/LTST-C190GKT.pdf"
			(at 0 0 270)
			(layer "F.Fab")
			(hide yes)
			(effects
				(font
					(size 1.27 1.27)
					(thickness 0.15)
				)
			)
		)
		(property "Description" "LED, Green, SMD, 0603, 20 mA, 2.1 V, 569 nm"
			(at 0 0 270)
			(layer "F.Fab")
			(hide yes)
			(effects
				(font
					(size 1.27 1.27)
					(thickness 0.15)
				)
			)
		)
		(property "Author" "Antmicro"
			(at 53.252 245.452 0)
			(layer "F.Fab")
			(hide yes)
			(effects
				(font
					(size 1 1)
					(thickness 0.15)
				)
			)
		)
		(property "Color" "Green"
			(at 53.252 245.452 0)
			(layer "F.Fab")
			(hide yes)
			(effects
				(font
					(size 1 1)
					(thickness 0.15)
				)
			)
		)
		(property "License" "Apache-2.0"
			(at 53.252 245.452 0)
			(layer "F.Fab")
			(hide yes)
			(effects
				(font
					(size 1 1)
					(thickness 0.15)
				)
			)
		)
		(property "MPN" "LTST-C190GKT"
			(at 53.252 245.452 0)
			(layer "F.Fab")
			(hide yes)
			(effects
				(font
					(size 1 1)
					(thickness 0.15)
				)
			)
		)
		(property "Manufacturer" "Lite-On"
			(at 53.252 245.452 0)
			(layer "F.Fab")
			(hide yes)
			(effects
				(font
					(size 1 1)
					(thickness 0.15)
				)
			)
		)
		(property "VSD_class" "LED"
			(at 53.252 245.452 0)
			(layer "F.Fab")
			(hide yes)
			(effects
				(font
					(size 1 1)
					(thickness 0.15)
				)
			)
		)
		(sheetname "/Power/")
		(sheetfile "power.kicad_sch")
		(attr smd)
		(fp_line
			(start 0.22 0.35)
			(end -0.22 0.35)
			(stroke
				(width 0.15)
				(type solid)
			)
			(layer "F.SilkS")
		)
		(fp_line
			(start -0.094672 0.201008)
			(end -0.094672 -0.198992)
			(stroke
				(width 0.1)
				(type solid)
			)
			(layer "F.SilkS")
		)
		(fp_line
			(start 0.105328 0.201008)
			(end -0.094672 0.001008)
			(stroke
				(width 0.1)
				(type solid)
			)
			(layer "F.SilkS")
		)
		(fp_line
			(start 0.105328 0.201008)
			(end 0.105328 -0.198992)
			(stroke
				(width 0.1)
				(type solid)
			)
			(layer "F.SilkS")
		)
		(fp_line
			(start -0.094672 0.001008)
			(end -0.24 0.001008)
			(stroke
				(width 0.1)
				(type solid)
			)
			(layer "F.SilkS")
		)
		(fp_line
			(start -0.094672 0.001008)
			(end 0.105328 -0.198992)
			(stroke
				(width 0.1)
				(type solid)
			)
			(layer "F.SilkS")
		)
		(fp_line
			(start 0.105328 0.001008)
			(end 0.24 0.001)
			(stroke
				(width 0.1)
				(type solid)
			)
			(layer "F.SilkS")
		)
		(fp_line
			(start -1.18 -0.319)
			(end -1.18 0.321)
			(stroke
				(width 0.15)
				(type solid)
			)
			(layer "F.SilkS")
		)
		(fp_line
			(start 0.22 -0.35)
			(end -0.22 -0.35)
			(stroke
				(width 0.15)
				(type solid)
			)
			(layer "F.SilkS")
		)
		(fp_rect
			(start 1.25 0.65)
			(end -1.25 -0.65)
			(stroke
				(width 0.05)
				(type solid)
			)
			(fill no)
			(layer "F.CrtYd")
		)
		(fp_line
			(start -0.199 0.2)
			(end -0.199 0.1)
			(stroke
				(width 0.15)
				(type solid)
			)
			(layer "F.Fab")
		)
		(fp_line
			(start 0.201 0.2)
			(end 0.201 0)
			(stroke
				(width 0.15)
				(type solid)
			)
			(layer "F.Fab")
		)
		(fp_line
			(start -0.199 0)
			(end -0.597 0)
			(stroke
				(width 0.15)
				(type solid)
			)
			(layer "F.Fab")
		)
		(fp_line
			(start -0.101 0)
			(end 0.201 0.2)
			(stroke
				(width 0.15)
				(type solid)
			)
			(layer "F.Fab")
		)
		(fp_line
			(start 0.201 0)
			(end 0.201 -0.202)
			(stroke
				(width 0.15)
				(type solid)
			)
			(layer "F.Fab")
		)
		(fp_line
			(start 0.599 0)
			(end 0.201 0)
			(stroke
				(width 0.15)
				(type solid)
			)
			(layer "F.Fab")
		)
		(fp_line
			(start -0.199 -0.202)
			(end -0.199 0.1)
			(stroke
				(width 0.15)
				(type solid)
			)
			(layer "F.Fab")
		)
		(fp_line
			(start 0.201 -0.202)
			(end -0.101 0)
			(stroke
				(width 0.15)
				(type solid)
			)
			(layer "F.Fab")
		)
		(fp_rect
			(start 0.848 0.4)
			(end -0.85 -0.402)
			(stroke
				(width 0.15)
				(type solid)
			)
			(fill no)
			(layer "F.Fab")
		)
		(pad "1" smd roundrect
			(at -0.7 0 90)
			(size 0.8 1)
			(layers "F.Cu" "F.Mask" "F.Paste")
			(roundrect_rratio 0.2)
			(net 141 "Net-(D17-C)")
			(pinfunction "C")
			(pintype "passive")
		)
		(pad "2" smd roundrect
			(at 0.7 0 90)
			(size 0.8 1)
			(layers "F.Cu" "F.Mask" "F.Paste")
			(roundrect_rratio 0.2)
			(net 4 "+12V")
			(pinfunction "A")
			(pintype "passive")
		)
	)
	(footprint "antmicro-footprints:R_0402_1005Metric"
		(layer "F.Cu")
		(at 184.077 52.7328 90)
		(descr "Resistor SMD 0402")
		(tags "resistor SMD 0402")
		(property "Reference" "R33"
			(at -1.27 -0.761 90)
			(layer "F.SilkS")
			(effects
				(font
					(size 0.7 0.7)
					(thickness 0.15)
				)
				(justify left bottom)
			)
		)
		(property "Value" "R_10k_0402"
			(at -1.011843 1.772047 90)
			(layer "F.Fab")
			(effects
				(font
					(size 0.7 0.7)
					(thickness 0.15)
				)
				(justify left bottom)
			)
		)
		(property "Datasheet" "https://www.bourns.com/docs/product-datasheets/cr.pdf"
			(at 0 0 90)
			(layer "F.Fab")
			(hide yes)
			(effects
				(font
					(size 1.27 1.27)
					(thickness 0.15)
				)
			)
		)
		(property "Description" "SMD Chip Resistor, 10 kohm, ± 1%, 62.5 mW, 0402 [1005 Metric], Thick Film, General Purpose"
			(at 0 0 90)
			(layer "F.Fab")
			(hide yes)
			(effects
				(font
					(size 1.27 1.27)
					(thickness 0.15)
				)
			)
		)
		(property "Author" "Antmicro"
			(at 236.8098 -131.3442 0)
			(layer "F.Fab")
			(hide yes)
			(effects
				(font
					(size 1 1)
					(thickness 0.15)
				)
			)
		)
		(property "License" "Apache-2.0"
			(at 236.8098 -131.3442 0)
			(layer "F.Fab")
			(hide yes)
			(effects
				(font
					(size 1 1)
					(thickness 0.15)
				)
			)
		)
		(property "MPN" "CR0402-FX-1002GLF"
			(at 236.8098 -131.3442 0)
			(layer "F.Fab")
			(hide yes)
			(effects
				(font
					(size 1 1)
					(thickness 0.15)
				)
			)
		)
		(property "Manufacturer" "Bourns"
			(at 236.8098 -131.3442 0)
			(layer "F.Fab")
			(hide yes)
			(effects
				(font
					(size 1 1)
					(thickness 0.15)
				)
			)
		)
		(property "Tolerance" "1%"
			(at 236.8098 -131.3442 0)
			(layer "F.Fab")
			(hide yes)
			(effects
				(font
					(size 1 1)
					(thickness 0.15)
				)
			)
		)
		(property "Val" "10k"
			(at 236.8098 -131.3442 0)
			(layer "F.Fab")
			(hide yes)
			(effects
				(font
					(size 1 1)
					(thickness 0.15)
				)
			)
		)
		(sheetname "/Power/")
		(sheetfile "power.kicad_sch")
		(attr smd)
		(fp_rect
			(start -0.925 -0.47)
			(end 0.925 0.47)
			(stroke
				(width 0.05)
				(type default)
			)
			(fill no)
			(layer "F.CrtYd")
		)
		(fp_rect
			(start -0.5 -0.25)
			(end 0.5 0.25)
			(stroke
				(width 0.15)
				(type solid)
			)
			(fill no)
			(layer "F.Fab")
		)
		(pad "1" smd roundrect
			(at -0.48 0 90)
			(size 0.59 0.64)
			(layers "F.Cu" "F.Mask" "F.Paste")
			(roundrect_rratio 0.25)
			(net 63 "/Power/FFC_5V_EN")
			(pintype "passive")
		)
		(pad "2" smd roundrect
			(at 0.48 0 90)
			(size 0.59 0.64)
			(layers "F.Cu" "F.Mask" "F.Paste")
			(roundrect_rratio 0.25)
			(net 113 "/Connectors/FFC_5V")
			(pintype "passive")
		)
	)
	(footprint "antmicro-footprints:LED_0603_1608Metric_G"
		(layer "F.Cu")
		(at 155.448 96.11 -90)
		(descr "LED SMD 0603 Green")
		(tags "LED SMD 0603 Green")
		(property "Reference" "D13"
			(at 0.062223 37.031333 0)
			(layer "F.SilkS")
			(effects
				(font
					(size 0.7 0.7)
					(thickness 0.15)
				)
				(justify right bottom)
			)
		)
		(property "Value" "LED_G_0603_LTST-C190GKT"
			(at -0.001 1.599 90)
			(layer "F.Fab")
			(effects
				(font
					(size 0.7 0.7)
					(thickness 0.15)
				)
				(justify right bottom)
			)
		)
		(property "Datasheet" "https://media.digikey.com/pdf/Data%20Sheets/Lite-On%20PDFs/LTST-C190GKT.pdf"
			(at 0 0 270)
			(layer "F.Fab")
			(hide yes)
			(effects
				(font
					(size 1.27 1.27)
					(thickness 0.15)
				)
			)
		)
		(property "Description" "LED, Green, SMD, 0603, 20 mA, 2.1 V, 569 nm"
			(at 0 0 270)
			(layer "F.Fab")
			(hide yes)
			(effects
				(font
					(size 1.27 1.27)
					(thickness 0.15)
				)
			)
		)
		(property "Author" "Antmicro"
			(at 59.338 251.558 0)
			(layer "F.Fab")
			(hide yes)
			(effects
				(font
					(size 1 1)
					(thickness 0.15)
				)
			)
		)
		(property "Color" "Green"
			(at 59.338 251.558 0)
			(layer "F.Fab")
			(hide yes)
			(effects
				(font
					(size 1 1)
					(thickness 0.15)
				)
			)
		)
		(property "License" "Apache-2.0"
			(at 59.338 251.558 0)
			(layer "F.Fab")
			(hide yes)
			(effects
				(font
					(size 1 1)
					(thickness 0.15)
				)
			)
		)
		(property "MPN" "LTST-C190GKT"
			(at 59.338 251.558 0)
			(layer "F.Fab")
			(hide yes)
			(effects
				(font
					(size 1 1)
					(thickness 0.15)
				)
			)
		)
		(property "Manufacturer" "Lite-On"
			(at 59.338 251.558 0)
			(layer "F.Fab")
			(hide yes)
			(effects
				(font
					(size 1 1)
					(thickness 0.15)
				)
			)
		)
		(property "VSD_class" "LED"
			(at 59.338 251.558 0)
			(layer "F.Fab")
			(hide yes)
			(effects
				(font
					(size 1 1)
					(thickness 0.15)
				)
			)
		)
		(sheetname "/Connectors/")
		(sheetfile "connectors.kicad_sch")
		(attr smd)
		(fp_line
			(start 0.22 0.35)
			(end -0.22 0.35)
			(stroke
				(width 0.15)
				(type solid)
			)
			(layer "F.SilkS")
		)
		(fp_line
			(start -0.094672 0.201008)
			(end -0.094672 -0.198992)
			(stroke
				(width 0.1)
				(type solid)
			)
			(layer "F.SilkS")
		)
		(fp_line
			(start 0.105328 0.201008)
			(end -0.094672 0.001008)
			(stroke
				(width 0.1)
				(type solid)
			)
			(layer "F.SilkS")
		)
		(fp_line
			(start 0.105328 0.201008)
			(end 0.105328 -0.198992)
			(stroke
				(width 0.1)
				(type solid)
			)
			(layer "F.SilkS")
		)
		(fp_line
			(start -0.094672 0.001008)
			(end -0.24 0.001008)
			(stroke
				(width 0.1)
				(type solid)
			)
			(layer "F.SilkS")
		)
		(fp_line
			(start -0.094672 0.001008)
			(end 0.105328 -0.198992)
			(stroke
				(width 0.1)
				(type solid)
			)
			(layer "F.SilkS")
		)
		(fp_line
			(start 0.105328 0.001008)
			(end 0.24 0.001)
			(stroke
				(width 0.1)
				(type solid)
			)
			(layer "F.SilkS")
		)
		(fp_line
			(start -1.18 -0.319)
			(end -1.18 0.321)
			(stroke
				(width 0.15)
				(type solid)
			)
			(layer "F.SilkS")
		)
		(fp_line
			(start 0.22 -0.35)
			(end -0.22 -0.35)
			(stroke
				(width 0.15)
				(type solid)
			)
			(layer "F.SilkS")
		)
		(fp_rect
			(start 1.25 0.65)
			(end -1.25 -0.65)
			(stroke
				(width 0.05)
				(type solid)
			)
			(fill no)
			(layer "F.CrtYd")
		)
		(fp_line
			(start -0.199 0.2)
			(end -0.199 0.1)
			(stroke
				(width 0.15)
				(type solid)
			)
			(layer "F.Fab")
		)
		(fp_line
			(start 0.201 0.2)
			(end 0.201 0)
			(stroke
				(width 0.15)
				(type solid)
			)
			(layer "F.Fab")
		)
		(fp_line
			(start -0.199 0)
			(end -0.597 0)
			(stroke
				(width 0.15)
				(type solid)
			)
			(layer "F.Fab")
		)
		(fp_line
			(start -0.101 0)
			(end 0.201 0.2)
			(stroke
				(width 0.15)
				(type solid)
			)
			(layer "F.Fab")
		)
		(fp_line
			(start 0.201 0)
			(end 0.201 -0.202)
			(stroke
				(width 0.15)
				(type solid)
			)
			(layer "F.Fab")
		)
		(fp_line
			(start 0.599 0)
			(end 0.201 0)
			(stroke
				(width 0.15)
				(type solid)
			)
			(layer "F.Fab")
		)
		(fp_line
			(start -0.199 -0.202)
			(end -0.199 0.1)
			(stroke
				(width 0.15)
				(type solid)
			)
			(layer "F.Fab")
		)
		(fp_line
			(start 0.201 -0.202)
			(end -0.101 0)
			(stroke
				(width 0.15)
				(type solid)
			)
			(layer "F.Fab")
		)
		(fp_rect
			(start 0.848 0.4)
			(end -0.85 -0.402)
			(stroke
				(width 0.15)
				(type solid)
			)
			(fill no)
			(layer "F.Fab")
		)
		(pad "1" smd roundrect
			(at -0.7 0 90)
			(size 0.8 1)
			(layers "F.Cu" "F.Mask" "F.Paste")
			(roundrect_rratio 0.2)
			(net 109 "Net-(D13-C)")
			(pinfunction "C")
			(pintype "passive")
		)
		(pad "2" smd roundrect
			(at 0.7 0 90)
			(size 0.8 1)
			(layers "F.Cu" "F.Mask" "F.Paste")
			(roundrect_rratio 0.2)
			(net 113 "/Connectors/FFC_5V")
			(pinfunction "A")
			(pintype "passive")
		)
	)
	(footprint "antmicro-footprints:R_0402_1005Metric"
		(layer "F.Cu")
		(at 143.692 73.66 -90)
		(descr "Resistor SMD 0402")
		(tags "resistor SMD 0402")
		(property "Reference" "R54"
			(at -3.0226 1.325 270)
			(layer "F.SilkS")
			(effects
				(font
					(size 0.7 0.7)
					(thickness 0.15)
				)
				(justify right bottom)
			)
		)
		(property "Value" "R_402R_0402"
			(at -1.011843 1.772047 90)
			(layer "F.Fab")
			(effects
				(font
					(size 0.7 0.7)
					(thickness 0.15)
				)
				(justify right bottom)
			)
		)
		(property "Datasheet" "https://www.mouser.com/datasheet/2/54/cr-1858361.pdf"
			(at 0 0 270)
			(layer "F.Fab")
			(hide yes)
			(effects
				(font
					(size 1.27 1.27)
					(thickness 0.15)
				)
			)
		)
		(property "Description" "SMD Chip Resistor, 402 ohm, ± 1%, 63 mW, 0402 [1005 Metric], Thick Film, General Purpose"
			(at 0 0 270)
			(layer "F.Fab")
			(hide yes)
			(effects
				(font
					(size 1.27 1.27)
					(thickness 0.15)
				)
			)
		)
		(property "Author" "Antmicro"
			(at 70.032 217.352 0)
			(layer "F.Fab")
			(hide yes)
			(effects
				(font
					(size 1 1)
					(thickness 0.15)
				)
			)
		)
		(property "License" "Apache-2.0"
			(at 70.032 217.352 0)
			(layer "F.Fab")
			(hide yes)
			(effects
				(font
					(size 1 1)
					(thickness 0.15)
				)
			)
		)
		(property "MPN" "CR0402-FX-4020GLF"
			(at 70.032 217.352 0)
			(layer "F.Fab")
			(hide yes)
			(effects
				(font
					(size 1 1)
					(thickness 0.15)
				)
			)
		)
		(property "Manufacturer" "Bourns"
			(at 70.032 217.352 0)
			(layer "F.Fab")
			(hide yes)
			(effects
				(font
					(size 1 1)
					(thickness 0.15)
				)
			)
		)
		(property "Tolerance" "1%"
			(at 70.032 217.352 0)
			(layer "F.Fab")
			(hide yes)
			(effects
				(font
					(size 1 1)
					(thickness 0.15)
				)
			)
		)
		(property "Val" "402R"
			(at 70.032 217.352 0)
			(layer "F.Fab")
			(hide yes)
			(effects
				(font
					(size 1 1)
					(thickness 0.15)
				)
			)
		)
		(sheetname "/Deserializer/")
		(sheetfile "deserializer.kicad_sch")
		(attr smd)
		(fp_rect
			(start -0.925 -0.47)
			(end 0.925 0.47)
			(stroke
				(width 0.05)
				(type default)
			)
			(fill no)
			(layer "F.CrtYd")
		)
		(fp_rect
			(start -0.5 -0.25)
			(end 0.5 0.25)
			(stroke
				(width 0.15)
				(type solid)
			)
			(fill no)
			(layer "F.Fab")
		)
		(pad "1" smd roundrect
			(at -0.48 0 270)
			(size 0.59 0.64)
			(layers "F.Cu" "F.Mask" "F.Paste")
			(roundrect_rratio 0.25)
			(net 1 "GND")
			(pintype "passive")
		)
		(pad "2" smd roundrect
			(at 0.48 0 270)
			(size 0.59 0.64)
			(layers "F.Cu" "F.Mask" "F.Paste")
			(roundrect_rratio 0.25)
			(net 78 "/Deserializer/XRES")
			(pintype "passive")
		)
	)
	(footprint "antmicro-footprints:C_0402_1005Metric"
		(layer "F.Cu")
		(at 139.827 76.581 135)
		(descr "Capacitor SMD 0402")
		(tags "capacitor SMD 0402")
		(property "Reference" "C27"
			(at 6.272037 -0.486489 315)
			(unlocked yes)
			(layer "F.SilkS")
			(effects
				(font
					(size 0.7 0.7)
					(thickness 0.15)
				)
				(justify left bottom)
			)
		)
		(property "Value" "C_100n_0402"
			(at -21.596927 15.617213 135)
			(layer "F.Fab")
			(effects
				(font
					(size 0.7 0.7)
					(thickness 0.15)
				)
				(justify left bottom)
			)
		)
		(property "Datasheet" "https://www.murata.com/products/productdetail?partno=GRM155R61H104KE14%23"
			(at 0 0 135)
			(layer "F.Fab")
			(hide yes)
			(effects
				(font
					(size 1.27 1.27)
					(thickness 0.15)
				)
			)
		)
		(property "Description" "SMD Multilayer Ceramic Capacitor, 0.1 µF, 50 V, 0402 [1005 Metric], ± 10%, X5R, GRM Series"
			(at 0 0 135)
			(layer "F.Fab")
			(hide yes)
			(effects
				(font
					(size 1.27 1.27)
					(thickness 0.15)
				)
			)
		)
		(property "Author" "Antmicro"
			(at 292.850564 31.859325 0)
			(layer "F.Fab")
			(hide yes)
			(effects
				(font
					(size 1 1)
					(thickness 0.15)
				)
			)
		)
		(property "Dielectric" "X5R"
			(at 292.850564 31.859325 0)
			(layer "F.Fab")
			(hide yes)
			(effects
				(font
					(size 1 1)
					(thickness 0.15)
				)
			)
		)
		(property "License" "Apache-2.0"
			(at 292.850564 31.859325 0)
			(layer "F.Fab")
			(hide yes)
			(effects
				(font
					(size 1 1)
					(thickness 0.15)
				)
			)
		)
		(property "MPN" "GRM155R61H104KE14D"
			(at 292.850564 31.859325 0)
			(layer "F.Fab")
			(hide yes)
			(effects
				(font
					(size 1 1)
					(thickness 0.15)
				)
			)
		)
		(property "Manufacturer" "Murata"
			(at 292.850564 31.859325 0)
			(layer "F.Fab")
			(hide yes)
			(effects
				(font
					(size 1 1)
					(thickness 0.15)
				)
			)
		)
		(property "Val" "100n"
			(at 292.850564 31.859325 0)
			(layer "F.Fab")
			(hide yes)
			(effects
				(font
					(size 1 1)
					(thickness 0.15)
				)
			)
		)
		(property "Voltage" "50V"
			(at 292.850564 31.859325 0)
			(layer "F.Fab")
			(hide yes)
			(effects
				(font
					(size 1 1)
					(thickness 0.15)
				)
			)
		)
		(sheetname "/Deserializer/")
		(sheetfile "deserializer.kicad_sch")
		(attr smd)
		(fp_poly
			(pts
				(xy -0.925 -0.47) (xy 0.925 -0.47) (xy 0.925 0.47) (xy -0.925 0.47)
			)
			(stroke
				(width 0.05)
				(type default)
			)
			(fill no)
			(layer "F.CrtYd")
		)
		(fp_line
			(start 0.504 -0.25)
			(end 0.504 0.248)
			(stroke
				(width 0.15)
				(type solid)
			)
			(layer "F.Fab")
		)
		(fp_line
			(start 0.504 0.248)
			(end -0.494 0.248)
			(stroke
				(width 0.15)
				(type solid)
			)
			(layer "F.Fab")
		)
		(fp_line
			(start -0.494 -0.25)
			(end 0.504 -0.25)
			(stroke
				(width 0.15)
				(type solid)
			)
			(layer "F.Fab")
		)
		(fp_line
			(start -0.494 0.248)
			(end -0.494 -0.25)
			(stroke
				(width 0.15)
				(type solid)
			)
			(layer "F.Fab")
		)
		(pad "1" smd roundrect
			(at -0.48 0 135)
			(size 0.59 0.64)
			(layers "F.Cu" "F.Mask" "F.Paste")
			(roundrect_rratio 0.25)
			(net 13 "/Deserializer/SIOA_P")
			(pintype "passive")
		)
		(pad "2" smd roundrect
			(at 0.48 0 135)
			(size 0.59 0.64)
			(layers "F.Cu" "F.Mask" "F.Paste")
			(roundrect_rratio 0.25)
			(net 114 "/Connectors/PoCA")
			(pintype "passive")
		)
	)
)
